FILE_TYPE = MACRO_DRAWING;
SET COLOR_WIRE YELLOW;
SET COLOR_PROP MONO;
SET COLOR_DOT WHITE;
SET COLOR_ARC YELLOW;
SET COLOR_BODY GREEN;
SET COLOR_NOTE MONO;
SET PROP_DISPLAY VALUE;
SET PAGE_NUMBER P11;
FORCEADD INTEL_CORP_BPAGE..1
(4250 200);
FORCEPROP 1 LAST CUSTOM_TXT_CDS <CURRENT_DESIGN_SHEET> OF <TOTAL_DESIGN_SHEETS>
J 0
(3750 225);
PAINT GREEN (3750 225);
FORCEPROP 1 LAST CUSTOM_TXT_CDS <CON_LAST_MODIFIED>
J 0
(2325 550);
PAINT GREEN (2325 550);
FORCEPROP 2 LAST CUSTOM_TXT_CDS <XR_PAGE_TITLE>
J 0
(-3640 5450);
DISPLAY 0.638298 (-3640 5450);
PAINT PINK (-3640 5450);
DISPLAY INVISIBLE (-3640 5450);
FORCEPROP 1 LAST SCH_ADDRESS3 Santa Clara, CA 95052-8119
J 0
(275 225);
DISPLAY 0.617021 (275 225);
PAINT GREEN (275 225);
FORCEPROP 1 LAST SCH_ADDRESS2 P.O. BOX 58119
J 0
(275 275);
DISPLAY 0.617021 (275 275);
PAINT GREEN (275 275);
FORCEPROP 1 LAST SCH_ADDRESS1 2200 Mission College Blvd.
J 0
(275 325);
DISPLAY 0.617021 (275 325);
PAINT GREEN (275 325);
FORCEPROP 1 LAST SCH_TITLE FAN BLOCK DIAGRAM
J 0
(-3700 250);
DISPLAY 1.212766 (-3700 250);
PAINT ORANGE (-3700 250);
FORCEPROP 1 LAST SCH_NUMBER H4694802
J 0
(2950 350);
DISPLAY 1.212766 (2950 350);
PAINT YELLOW (2950 350);
FORCEPROP 1 LAST SCH_DEPT BESD
J 1
(-200 300);
DISPLAY 1.212766 (-200 300);
PAINT YELLOW (-200 300);
FORCEPROP 1 LAST SCH_REV 2.420
J 0
(4000 350);
DISPLAY 0.978723 (4000 350);
PAINT YELLOW (4000 350);
FORCEPROP 2 LAST CDS_LIB mstr_symbols
J 0
(4250 200);
PAINT MONO (4250 200);
DISPLAY INVISIBLE (4250 200);
FORCEPROP 2 LAST PAGE_BORDER TRUE
J 0
(-3640 5450);
DISPLAY 0.638298 (-3640 5450);
PAINT PINK (-3640 5450);
DISPLAY INVISIBLE (-3640 5450);
FORCEPROP 1 LAST COMMENT_BODY TRUE
J 0
(4262 212);
DISPLAY 0.468085 (4262 212);
PAINT GREEN (4262 212);
DISPLAY INVISIBLE (4262 212);
FORCEPROP 1 LAST CDS_CON_LAST_MODIFIED Tue Dec 01 11:47:57 2015
J 0
(2825 525);
PAINT ORANGE (2825 525);
DISPLAY INVISIBLE (2825 525);
FORCEPROP 2 LAST CDS_XR_PAGE_TITLE CR-11 : @BASEBOARD_FAB2_LIB.BASEBOARD_FAB2(SCH_1):PAGE11
J 0
(-3640 5450);
DISPLAY 0.638298 (-3640 5450);
PAINT PINK (-3640 5450);
DISPLAY INVISIBLE (-3640 5450);
FORCENOTE
$CDS_IMAGE|11_FAN.jpg|4486|4131
(150 2875) 0;
DISPLAY CENTER (150 2875);
PAINT MONO (150 2875);
QUIT
